(kicad_pcb
	(version 20240108)
	(generator "pcbnew")
	(generator_version "8.0")
	(general
		(thickness 1.586)
		(legacy_teardrops no)
	)
	(paper "A4")
	(title_block
		(title "GMSL Serializer")
		(date "2024-11-27")
		(rev "1.1.1")
		(company "Antmicro Ltd")
		(comment 1 "www.antmicro.com")
		(comment 9 "footprints 5-9 of 117")
	)
	(layers
		(0 "F.Cu" signal)
		(1 "In1.Cu" power)
		(2 "In2.Cu" power)
		(31 "B.Cu" signal)
		(32 "B.Adhes" user "B.Adhesive")
		(33 "F.Adhes" user "F.Adhesive")
		(34 "B.Paste" user)
		(35 "F.Paste" user)
		(36 "B.SilkS" user "B.Silkscreen")
		(37 "F.SilkS" user "F.Silkscreen")
		(38 "B.Mask" user)
		(39 "F.Mask" user)
		(40 "Dwgs.User" user "User.Drawings")
		(41 "Cmts.User" user "User.Comments")
		(42 "Eco1.User" user "User.Eco1")
		(43 "Eco2.User" user "User.Eco2")
		(44 "Edge.Cuts" user)
		(45 "Margin" user)
		(46 "B.CrtYd" user "B.Courtyard")
		(47 "F.CrtYd" user "F.Courtyard")
		(48 "B.Fab" user)
		(49 "F.Fab" user)
	)
	(footprint "antmicro-footprints:TP_SMD_1.5mm"
		(layer "F.Cu")
		(at 163.55 111.35)
		(property "Reference" "TP9"
			(at 0 -0.9 0)
			(layer "F.SilkS")
			(hide yes)
			(effects
				(font
					(size 0.7 0.7)
					(thickness 0.15)
				)
				(justify left bottom)
			)
		)
		(property "Value" "TP_1.5mm_SMD"
			(at 0 1.7 0)
			(layer "F.Fab")
			(effects
				(font
					(size 0.7 0.7)
					(thickness 0.15)
				)
				(justify left bottom)
			)
		)
		(property "Footprint" "antmicro-footprints:TP_SMD_1.5mm"
			(at 0 0 0)
			(layer "F.Fab")
			(hide yes)
			(effects
				(font
					(size 1.27 1.27)
					(thickness 0.15)
				)
			)
		)
		(property "Author" "Antmicro"
			(at 0 0 0)
			(layer "F.Fab")
			(hide yes)
			(effects
				(font
					(size 1 1)
					(thickness 0.15)
				)
			)
		)
		(property "License" "Apache-2.0"
			(at 0 0 0)
			(layer "F.Fab")
			(hide yes)
			(effects
				(font
					(size 1 1)
					(thickness 0.15)
				)
			)
		)
		(property "MPN" ""
			(at 0 0 0)
			(layer "F.Fab")
			(hide yes)
			(effects
				(font
					(size 1 1)
					(thickness 0.15)
				)
			)
		)
		(property "Manufacturer" ""
			(at 0 0 0)
			(layer "F.Fab")
			(hide yes)
			(effects
				(font
					(size 1 1)
					(thickness 0.15)
				)
			)
		)
		(sheetname "Supply")
		(sheetfile "supply.kicad_sch")
		(attr exclude_from_pos_files exclude_from_bom)
		(fp_circle
			(center 0 0)
			(end 0.85 0)
			(stroke
				(width 0.05)
				(type default)
			)
			(fill none)
			(layer "F.CrtYd")
		)
		(fp_text user "Author: Antmicro"
			(at -0.7 4.101 0)
			(layer "F.Fab")
			(hide yes)
			(effects
				(font
					(size 0.7 0.7)
					(thickness 0.15)
				)
				(justify left bottom)
			)
		)
		(fp_text user "${REFERENCE}"
			(at -0.7 2.9 0)
			(layer "F.Fab")
			(hide yes)
			(effects
				(font
					(size 0.7 0.7)
					(thickness 0.15)
				)
				(justify left bottom)
			)
		)
		(fp_text user "License: Apache-2.0"
			(at -0.7 5.301 0)
			(layer "F.Fab")
			(hide yes)
			(effects
				(font
					(size 0.7 0.7)
					(thickness 0.15)
				)
				(justify left bottom)
			)
		)
		(pad "1" smd circle
			(at 0 0 270)
			(size 1.5 1.5)
			(layers "F.Cu" "F.Mask")
			(net 1 "GND")
			(pinfunction "1")
			(pintype "passive")
		)
	)
	(footprint "antmicro-footprints:TP_SMD_1.5mm"
		(layer "F.Cu")
		(at 158.75 118)
		(property "Reference" "TP7"
			(at -0.4 -1.139684 0)
			(layer "F.SilkS")
			(hide yes)
			(effects
				(font
					(size 0.7 0.7)
					(thickness 0.15)
				)
				(justify left bottom)
			)
		)
		(property "Value" "TP_1.5mm_SMD"
			(at 0 1.7 0)
			(layer "F.Fab")
			(effects
				(font
					(size 0.7 0.7)
					(thickness 0.15)
				)
				(justify left bottom)
			)
		)
		(property "Footprint" "antmicro-footprints:TP_SMD_1.5mm"
			(at 0 0 0)
			(layer "F.Fab")
			(hide yes)
			(effects
				(font
					(size 1.27 1.27)
					(thickness 0.15)
				)
			)
		)
		(property "Author" "Antmicro"
			(at 0 0 0)
			(layer "F.Fab")
			(hide yes)
			(effects
				(font
					(size 1 1)
					(thickness 0.15)
				)
			)
		)
		(property "License" "Apache-2.0"
			(at 0 0 0)
			(layer "F.Fab")
			(hide yes)
			(effects
				(font
					(size 1 1)
					(thickness 0.15)
				)
			)
		)
		(property "MPN" ""
			(at 0 0 0)
			(layer "F.Fab")
			(hide yes)
			(effects
				(font
					(size 1 1)
					(thickness 0.15)
				)
			)
		)
		(property "Manufacturer" ""
			(at 0 0 0)
			(layer "F.Fab")
			(hide yes)
			(effects
				(font
					(size 1 1)
					(thickness 0.15)
				)
			)
		)
		(sheetname "Serializer")
		(sheetfile "serializer.kicad_sch")
		(attr exclude_from_pos_files exclude_from_bom)
		(fp_circle
			(center 0 0)
			(end 0.85 0)
			(stroke
				(width 0.05)
				(type default)
			)
			(fill none)
			(layer "F.CrtYd")
		)
		(fp_text user "Author: Antmicro"
			(at -0.7 4.101 0)
			(layer "F.Fab")
			(hide yes)
			(effects
				(font
					(size 0.7 0.7)
					(thickness 0.15)
				)
				(justify left bottom)
			)
		)
		(fp_text user "License: Apache-2.0"
			(at -0.7 5.301 0)
			(layer "F.Fab")
			(hide yes)
			(effects
				(font
					(size 0.7 0.7)
					(thickness 0.15)
				)
				(justify left bottom)
			)
		)
		(fp_text user "${REFERENCE}"
			(at -0.7 2.9 0)
			(layer "F.Fab")
			(hide yes)
			(effects
				(font
					(size 0.7 0.7)
					(thickness 0.15)
				)
				(justify left bottom)
			)
		)
		(pad "1" smd circle
			(at 0 0 270)
			(size 1.5 1.5)
			(layers "F.Cu" "F.Mask")
			(net 84 "Net-(U6-MFP5)")
			(pinfunction "1")
			(pintype "passive")
		)
	)
	(footprint "antmicro-footprints:LED_0603_1608Metric_G"
		(layer "F.Cu")
		(at 142.25 115.75 -90)
		(descr "LED SMD 0603 Green")
		(tags "LED SMD 0603 Green")
		(property "Reference" "D5"
			(at -2.725 -0.425 90)
			(layer "F.SilkS")
			(effects
				(font
					(size 0.7 0.7)
					(thickness 0.15)
				)
				(justify right bottom)
			)
		)
		(property "Value" "LED_G_0603_LTST-C190GKT"
			(at -0.001 1.599 90)
			(layer "F.Fab")
			(effects
				(font
					(size 0.7 0.7)
					(thickness 0.15)
				)
				(justify right bottom)
			)
		)
		(property "Footprint" "antmicro-footprints:LED_0603_1608Metric_G"
			(at 0 0 -90)
			(layer "F.Fab")
			(hide yes)
			(effects
				(font
					(size 1.27 1.27)
					(thickness 0.15)
				)
			)
		)
		(property "Datasheet" "https://media.digikey.com/pdf/Data%20Sheets/Lite-On%20PDFs/LTST-C190GKT.pdf"
			(at 0 0 -90)
			(layer "F.Fab")
			(hide yes)
			(effects
				(font
					(size 1.27 1.27)
					(thickness 0.15)
				)
			)
		)
		(property "Author" "Antmicro"
			(at 26.5 258 0)
			(layer "F.Fab")
			(hide yes)
			(effects
				(font
					(size 1 1)
					(thickness 0.15)
				)
			)
		)
		(property "Color" "Green"
			(at 26.5 258 0)
			(layer "F.Fab")
			(hide yes)
			(effects
				(font
					(size 1 1)
					(thickness 0.15)
				)
			)
		)
		(property "License" "Apache-2.0"
			(at 26.5 258 0)
			(layer "F.Fab")
			(hide yes)
			(effects
				(font
					(size 1 1)
					(thickness 0.15)
				)
			)
		)
		(property "MPN" "LTST-C190GKT"
			(at 26.5 258 0)
			(layer "F.Fab")
			(hide yes)
			(effects
				(font
					(size 1 1)
					(thickness 0.15)
				)
			)
		)
		(property "Manufacturer" "Lite-On"
			(at 26.5 258 0)
			(layer "F.Fab")
			(hide yes)
			(effects
				(font
					(size 1 1)
					(thickness 0.15)
				)
			)
		)
		(property "VSD_class" "LED"
			(at 26.5 258 0)
			(layer "F.Fab")
			(hide yes)
			(effects
				(font
					(size 1 1)
					(thickness 0.15)
				)
			)
		)
		(sheetname "Supply")
		(sheetfile "supply.kicad_sch")
		(attr smd)
		(fp_line
			(start 0.22 0.35)
			(end -0.22 0.35)
			(stroke
				(width 0.15)
				(type solid)
			)
			(layer "F.SilkS")
		)
		(fp_line
			(start -0.094672 0.201008)
			(end -0.094672 -0.198992)
			(stroke
				(width 0.1)
				(type solid)
			)
			(layer "F.SilkS")
		)
		(fp_line
			(start 0.105328 0.201008)
			(end -0.094672 0.001008)
			(stroke
				(width 0.1)
				(type solid)
			)
			(layer "F.SilkS")
		)
		(fp_line
			(start 0.105328 0.201008)
			(end 0.105328 -0.198992)
			(stroke
				(width 0.1)
				(type solid)
			)
			(layer "F.SilkS")
		)
		(fp_line
			(start -0.094672 0.001008)
			(end -0.24 0.001008)
			(stroke
				(width 0.1)
				(type solid)
			)
			(layer "F.SilkS")
		)
		(fp_line
			(start -0.094672 0.001008)
			(end 0.105328 -0.198992)
			(stroke
				(width 0.1)
				(type solid)
			)
			(layer "F.SilkS")
		)
		(fp_line
			(start 0.105328 0.001008)
			(end 0.24 0.001)
			(stroke
				(width 0.1)
				(type solid)
			)
			(layer "F.SilkS")
		)
		(fp_line
			(start -1.18 -0.319)
			(end -1.18 0.321)
			(stroke
				(width 0.15)
				(type solid)
			)
			(layer "F.SilkS")
		)
		(fp_line
			(start 0.22 -0.35)
			(end -0.22 -0.35)
			(stroke
				(width 0.15)
				(type solid)
			)
			(layer "F.SilkS")
		)
		(fp_rect
			(start 1.25 0.65)
			(end -1.25 -0.65)
			(stroke
				(width 0.05)
				(type solid)
			)
			(fill none)
			(layer "F.CrtYd")
		)
		(fp_line
			(start -0.199 0.2)
			(end -0.199 0.1)
			(stroke
				(width 0.15)
				(type solid)
			)
			(layer "F.Fab")
		)
		(fp_line
			(start 0.201 0.2)
			(end 0.201 0)
			(stroke
				(width 0.15)
				(type solid)
			)
			(layer "F.Fab")
		)
		(fp_line
			(start -0.199 0)
			(end -0.597 0)
			(stroke
				(width 0.15)
				(type solid)
			)
			(layer "F.Fab")
		)
		(fp_line
			(start -0.101 0)
			(end 0.201 0.2)
			(stroke
				(width 0.15)
				(type solid)
			)
			(layer "F.Fab")
		)
		(fp_line
			(start 0.201 0)
			(end 0.201 -0.202)
			(stroke
				(width 0.15)
				(type solid)
			)
			(layer "F.Fab")
		)
		(fp_line
			(start 0.599 0)
			(end 0.201 0)
			(stroke
				(width 0.15)
				(type solid)
			)
			(layer "F.Fab")
		)
		(fp_line
			(start -0.199 -0.202)
			(end -0.199 0.1)
			(stroke
				(width 0.15)
				(type solid)
			)
			(layer "F.Fab")
		)
		(fp_line
			(start 0.201 -0.202)
			(end -0.101 0)
			(stroke
				(width 0.15)
				(type solid)
			)
			(layer "F.Fab")
		)
		(fp_rect
			(start 0.848 0.4)
			(end -0.85 -0.402)
			(stroke
				(width 0.15)
				(type solid)
			)
			(fill none)
			(layer "F.Fab")
		)
		(fp_text user "License: Apache-2.0"
			(at -1.4224 3.599 90)
			(layer "F.Fab")
			(hide yes)
			(effects
				(font
					(size 0.7 0.7)
					(thickness 0.15)
				)
				(justify right bottom)
			)
		)
		(fp_text user "${REFERENCE}"
			(at -1.4224 5.999 90)
			(layer "F.Fab")
			(hide yes)
			(effects
				(font
					(size 0.7 0.7)
					(thickness 0.15)
				)
				(justify right bottom)
			)
		)
		(fp_text user "Author: Antmicro"
			(at -1.4224 4.799 90)
			(layer "F.Fab")
			(hide yes)
			(effects
				(font
					(size 0.7 0.7)
					(thickness 0.15)
				)
				(justify right bottom)
			)
		)
		(pad "1" smd roundrect
			(at -0.7 0 90)
			(size 0.8 1)
			(layers "F.Cu" "F.Paste" "F.Mask")
			(roundrect_rratio 0.2)
			(net 69 "Net-(D5-C)")
			(pinfunction "C")
			(pintype "passive")
		)
		(pad "2" smd roundrect
			(at 0.7 0 90)
			(size 0.8 1)
			(layers "F.Cu" "F.Paste" "F.Mask")
			(roundrect_rratio 0.2)
			(net 9 "+5V")
			(pinfunction "A")
			(pintype "passive")
		)
	)
	(footprint "antmicro-footprints:R_0402_1005Metric"
		(layer "F.Cu")
		(at 140.83 79.980142)
		(descr "Resistor SMD 0402")
		(tags "resistor SMD 0402")
		(property "Reference" "R44"
			(at -1.08 -0.480142 0)
			(layer "F.SilkS")
			(effects
				(font
					(size 0.7 0.7)
					(thickness 0.15)
				)
				(justify left bottom)
			)
		)
		(property "Value" "R_10k_0402"
			(at -1.011843 1.772047 0)
			(layer "F.Fab")
			(effects
				(font
					(size 0.7 0.7)
					(thickness 0.15)
				)
				(justify left bottom)
			)
		)
		(property "Footprint" "antmicro-footprints:R_0402_1005Metric"
			(at 0 0 0)
			(layer "F.Fab")
			(hide yes)
			(effects
				(font
					(size 1.27 1.27)
					(thickness 0.15)
				)
			)
		)
		(property "Datasheet" "https://www.bourns.com/docs/product-datasheets/cr.pdf"
			(at 0 0 0)
			(layer "F.Fab")
			(hide yes)
			(effects
				(font
					(size 1.27 1.27)
					(thickness 0.15)
				)
			)
		)
		(property "MPN" "CR0402-FX-1002GLF"
			(at 0 0 0)
			(unlocked yes)
			(layer "F.Fab")
			(hide yes)
			(effects
				(font
					(size 1 1)
					(thickness 0.15)
				)
			)
		)
		(property "Manufacturer" "Bourns"
			(at 0 0 0)
			(unlocked yes)
			(layer "F.Fab")
			(hide yes)
			(effects
				(font
					(size 1 1)
					(thickness 0.15)
				)
			)
		)
		(property "License" "Apache-2.0"
			(at 0 0 0)
			(unlocked yes)
			(layer "F.Fab")
			(hide yes)
			(effects
				(font
					(size 1 1)
					(thickness 0.15)
				)
			)
		)
		(property "Author" "Antmicro"
			(at 0 0 0)
			(unlocked yes)
			(layer "F.Fab")
			(hide yes)
			(effects
				(font
					(size 1 1)
					(thickness 0.15)
				)
			)
		)
		(property "Val" "10k"
			(at 0 0 0)
			(unlocked yes)
			(layer "F.Fab")
			(hide yes)
			(effects
				(font
					(size 1 1)
					(thickness 0.15)
				)
			)
		)
		(property "Tolerance" "1%"
			(at 0 0 0)
			(unlocked yes)
			(layer "F.Fab")
			(hide yes)
			(effects
				(font
					(size 1 1)
					(thickness 0.15)
				)
			)
		)
		(sheetname "Supply")
		(sheetfile "supply.kicad_sch")
		(attr smd)
		(fp_rect
			(start -0.925 -0.47)
			(end 0.925 0.47)
			(stroke
				(width 0.05)
				(type default)
			)
			(fill none)
			(layer "F.CrtYd")
		)
		(fp_rect
			(start -0.5 -0.25)
			(end 0.5 0.25)
			(stroke
				(width 0.15)
				(type solid)
			)
			(fill none)
			(layer "F.Fab")
		)
		(fp_text user "${REFERENCE}"
			(at -0.95 3.168 0)
			(layer "F.Fab")
			(hide yes)
			(effects
				(font
					(size 0.7 0.7)
					(thickness 0.15)
				)
				(justify left bottom)
			)
		)
		(fp_text user "License: Apache-2.0"
			(at -0.95 5.169 0)
			(layer "F.Fab")
			(hide yes)
			(effects
				(font
					(size 0.7 0.7)
					(thickness 0.15)
				)
				(justify left bottom)
			)
		)
		(fp_text user "Author: Antmicro"
			(at -0.95 4.169 0)
			(layer "F.Fab")
			(hide yes)
			(effects
				(font
					(size 0.7 0.7)
					(thickness 0.15)
				)
				(justify left bottom)
			)
		)
		(pad "1" smd roundrect
			(at -0.48 0)
			(size 0.59 0.64)
			(layers "F.Cu" "F.Paste" "F.Mask")
			(roundrect_rratio 0.25)
			(net 1 "GND")
			(pintype "passive")
		)
		(pad "2" smd roundrect
			(at 0.48 0)
			(size 0.59 0.64)
			(layers "F.Cu" "F.Paste" "F.Mask")
			(roundrect_rratio 0.25)
			(net 96 "/Supply/FB_3V3")
			(pintype "passive")
		)
	)
	(footprint "antmicro-footprints:R_0402_1005Metric"
		(layer "F.Cu")
		(at 135.4 108.75)
		(descr "Resistor SMD 0402")
		(tags "resistor SMD 0402")
		(property "Reference" "R33"
			(at 0.9 0.4125 0)
			(layer "F.SilkS")
			(effects
				(font
					(size 0.7 0.7)
					(thickness 0.15)
				)
				(justify left bottom)
			)
		)
		(property "Value" "R_0R_0402"
			(at -1.011843 1.772047 0)
			(layer "F.Fab")
			(effects
				(font
					(size 0.7 0.7)
					(thickness 0.15)
				)
				(justify left bottom)
			)
		)
		(property "Footprint" "antmicro-footprints:R_0402_1005Metric"
			(at 0 0 0)
			(layer "F.Fab")
			(hide yes)
			(effects
				(font
					(size 1.27 1.27)
					(thickness 0.15)
				)
			)
		)
		(property "Datasheet" "https://industrial.panasonic.com/cdbs/www-data/pdf/RDA0000/AOA0000C301.pdf"
			(at 0 0 0)
			(layer "F.Fab")
			(hide yes)
			(effects
				(font
					(size 1.27 1.27)
					(thickness 0.15)
				)
			)
		)
		(property "Author" "Antmicro"
			(at 0 0 0)
			(layer "F.Fab")
			(hide yes)
			(effects
				(font
					(size 1 1)
					(thickness 0.15)
				)
			)
		)
		(property "Current" "1A"
			(at 0 0 0)
			(layer "F.Fab")
			(hide yes)
			(effects
				(font
					(size 1 1)
					(thickness 0.15)
				)
			)
		)
		(property "License" "Apache-2.0"
			(at 0 0 0)
			(layer "F.Fab")
			(hide yes)
			(effects
				(font
					(size 1 1)
					(thickness 0.15)
				)
			)
		)
		(property "MPN" "ERJ2GE0R00X"
			(at 0 0 0)
			(layer "F.Fab")
			(hide yes)
			(effects
				(font
					(size 1 1)
					(thickness 0.15)
				)
			)
		)
		(property "Manufacturer" "Panasonic"
			(at 0 0 0)
			(layer "F.Fab")
			(hide yes)
			(effects
				(font
					(size 1 1)
					(thickness 0.15)
				)
			)
		)
		(property "Tolerance" ""
			(at 0 0 0)
			(layer "F.Fab")
			(hide yes)
			(effects
				(font
					(size 1 1)
					(thickness 0.15)
				)
			)
		)
		(property "Val" "0R"
			(at 0 0 0)
			(layer "F.Fab")
			(hide yes)
			(effects
				(font
					(size 1 1)
					(thickness 0.15)
				)
			)
		)
		(sheetname "Serializer")
		(sheetfile "serializer.kicad_sch")
		(attr smd)
		(fp_rect
			(start -0.925 -0.47)
			(end 0.925 0.47)
			(stroke
				(width 0.05)
				(type default)
			)
			(fill none)
			(layer "F.CrtYd")
		)
		(fp_rect
			(start -0.5 -0.25)
			(end 0.5 0.25)
			(stroke
				(width 0.15)
				(type solid)
			)
			(fill none)
			(layer "F.Fab")
		)
		(fp_text user "Author: Antmicro"
			(at -0.95 4.169 0)
			(layer "F.Fab")
			(hide yes)
			(effects
				(font
					(size 0.7 0.7)
					(thickness 0.15)
				)
				(justify left bottom)
			)
		)
		(fp_text user "${REFERENCE}"
			(at -0.95 3.168 0)
			(layer "F.Fab")
			(hide yes)
			(effects
				(font
					(size 0.7 0.7)
					(thickness 0.15)
				)
				(justify left bottom)
			)
		)
		(fp_text user "License: Apache-2.0"
			(at -0.95 5.169 0)
			(layer "F.Fab")
			(hide yes)
			(effects
				(font
					(size 0.7 0.7)
					(thickness 0.15)
				)
				(justify left bottom)
			)
		)
		(pad "1" smd roundrect
			(at -0.48 0)
			(size 0.59 0.64)
			(layers "F.Cu" "F.Paste" "F.Mask")
			(roundrect_rratio 0.25)
			(net 89 "/CSI Connector/I2C.SCL")
			(pintype "passive")
		)
		(pad "2" smd roundrect
			(at 0.48 0)
			(size 0.59 0.64)
			(layers "F.Cu" "F.Paste" "F.Mask")
			(roundrect_rratio 0.25)
			(net 82 "Net-(U6-MFP10)")
			(pintype "passive")
		)
	)
)
